# T6G (Grand Teton) — schematic netlist excerpt (pin names and nets, part order shuffled) for the footprints in the layout excerpt that follows; sources: Cadence DE-HDL packaged netlist, KiCad conversion of 04192023_DAF0TMB3IC0_F0TG_MB_C_brd_V02_OCP.brd

C716  Q_CAP_DIFFBUS  DIFF BUS_0.22UF 6.3V 20% X6S  pkg C0201  page 66 : \1\ = P5E_CPU1_P1_TX_C_DN<12> ; \2\ = P5E_CPU1_P1_TX_DN<12>
R1326  Q_RES  1K 1% EMPTY  pkg 0402LF  page 357 : A = P3V3_AUX ; B = E1S_0_P3V3_P12V_ADC_R_ALERT
R8094  Q_RES  0 5% CHIP  pkg 0402LF  page 136 : A = OCP_V3_1_P3V3_R1_PWRGD ; B = OCP_V3_1_P3V3_PWRGD

(kicad_pcb
	(version 20260206)
	(generator "pcbnew")
	(generator_version "10.0")
	(general
		(thickness 1.6)
		(legacy_teardrops no)
	)
	(paper "A4")
	(title_block
		(title "04192023_DAF0TMB3IC0_F0TG_MB_C_brd_V02_OCP.brd")
		(comment 1 "Grand Teton / footprints 4537-4539 of 8354")
	)
	(layers
		(0 "F.Cu" signal "TOP")
		(4 "In1.Cu" signal "GND")
		(6 "In2.Cu" signal "IN1")
		(8 "In3.Cu" signal "GND1")
		(10 "In4.Cu" signal "IN2")
		(12 "In5.Cu" signal "GND2")
		(14 "In6.Cu" signal "IN3")
		(16 "In7.Cu" signal "GND3")
		(18 "In8.Cu" signal "VCC")
		(20 "In9.Cu" signal "VCC1")
		(22 "In10.Cu" signal "GND4")
		(24 "In11.Cu" signal "IN4")
		(26 "In12.Cu" signal "GND5")
		(28 "In13.Cu" signal "IN5")
		(30 "In14.Cu" signal "GND6")
		(32 "In15.Cu" signal "IN6")
		(34 "In16.Cu" signal "GND7")
		(2 "B.Cu" signal "BOTTOM")
		(9 "F.Adhes" user "F.Adhesive")
		(11 "B.Adhes" user "B.Adhesive")
		(13 "F.Paste" user "Package Geometry/Pastemask Top")
		(15 "B.Paste" user "Package Geometry/Pastemask Bottom")
		(5 "F.SilkS" user "Ref Des/Silkscreen Top")
		(7 "B.SilkS" user "Ref Des/Silkscreen Bottom")
		(1 "F.Mask" user "Board Geometry/Soldermask Top")
		(3 "B.Mask" user "Board Geometry/Soldermask Bottom")
		(17 "Dwgs.User" user "User.Drawings")
		(19 "Cmts.User" user "User.Comments")
		(21 "Eco1.User" user "User.Eco1")
		(23 "Eco2.User" user "User.Eco2")
		(25 "Edge.Cuts" user "Board Geometry/Outline")
		(27 "Margin" user)
		(31 "F.CrtYd" user "Package Geometry/Place Bound Top")
		(29 "B.CrtYd" user "Package Geometry/Place Bound Bottom")
		(35 "F.Fab" user "Ref Des/Assembly Top")
		(33 "B.Fab" user "Ref Des/Assembly Bottom")
	)
	(footprint ""
		(layer "F.Cu")
		(at 321.106546 -100.36175 180)
		(property "Reference" "R1326"
			(at 0 0 180)
			(layer "F.SilkS")
			(hide yes)
			(effects
				(font
					(size 1.27 1.27)
				)
			)
		)
		(property "Value" ""
			(at 0 0 180)
			(layer "F.Fab")
			(effects
				(font
					(size 1.27 1.27)
				)
			)
		)
		(duplicate_pad_numbers_are_jumpers no)
		(fp_line
			(start 0.7874 0.4064)
			(end -0.7874 0.4064)
			(stroke
				(width 0.1524)
				(type default)
			)
			(layer "F.SilkS")
		)
		(fp_line
			(start 0.7874 -0.4064)
			(end 0.7874 0.4064)
			(stroke
				(width 0.1524)
				(type default)
			)
			(layer "F.SilkS")
		)
		(fp_line
			(start -0.7874 0.4064)
			(end -0.7874 -0.4064)
			(stroke
				(width 0.1524)
				(type default)
			)
			(layer "F.SilkS")
		)
		(fp_line
			(start -0.7874 -0.4064)
			(end 0.7874 -0.4064)
			(stroke
				(width 0.1524)
				(type default)
			)
			(layer "F.SilkS")
		)
		(fp_line
			(start 0.67945 0.3048)
			(end 0.120396 0.3048)
			(stroke
				(width 0.1)
				(type default)
			)
			(layer "F.Fab")
		)
		(fp_line
			(start 0.67945 -0.3048)
			(end 0.67945 0.3048)
			(stroke
				(width 0.1)
				(type default)
			)
			(layer "F.Fab")
		)
		(fp_line
			(start 0.12065 -0.2794)
			(end 0.12065 -0.3048)
			(stroke
				(width 0.1)
				(type default)
			)
			(layer "F.Fab")
		)
		(fp_line
			(start 0.12065 -0.3048)
			(end 0.67945 -0.3048)
			(stroke
				(width 0.1)
				(type default)
			)
			(layer "F.Fab")
		)
		(fp_line
			(start 0.120396 0.3048)
			(end 0.120396 0.2794)
			(stroke
				(width 0.1)
				(type default)
			)
			(layer "F.Fab")
		)
		(fp_line
			(start 0.120396 0.2794)
			(end -0.12065 0.2794)
			(stroke
				(width 0.1)
				(type default)
			)
			(layer "F.Fab")
		)
		(fp_line
			(start -0.12065 0.3048)
			(end -0.67945 0.3048)
			(stroke
				(width 0.1)
				(type default)
			)
			(layer "F.Fab")
		)
		(fp_line
			(start -0.12065 0.2794)
			(end -0.12065 0.3048)
			(stroke
				(width 0.1)
				(type default)
			)
			(layer "F.Fab")
		)
		(fp_line
			(start -0.12065 -0.2794)
			(end 0.12065 -0.2794)
			(stroke
				(width 0.1)
				(type default)
			)
			(layer "F.Fab")
		)
		(fp_line
			(start -0.12065 -0.305054)
			(end -0.12065 -0.2794)
			(stroke
				(width 0.1)
				(type default)
			)
			(layer "F.Fab")
		)
		(fp_line
			(start -0.67945 0.3048)
			(end -0.67945 -0.305054)
			(stroke
				(width 0.1)
				(type default)
			)
			(layer "F.Fab")
		)
		(fp_line
			(start -0.67945 -0.305054)
			(end -0.12065 -0.305054)
			(stroke
				(width 0.1)
				(type default)
			)
			(layer "F.Fab")
		)
		(pad "1" smd circle
			(at -0.40005 0 180)
			(size 0 0)
			(layers "F.Cu" "F.Mask" "F.Paste")
			(net "P3V3_AUX")
		)
		(pad "2" smd circle
			(at 0.40005 0 180)
			(size 0 0)
			(layers "F.Cu" "F.Mask" "F.Paste")
			(net "E1S_0_P3V3_P12V_ADC_R_ALERT")
		)
	)
	(footprint ""
		(layer "F.Cu")
		(at 98.555302 -370.57203 -90)
		(property "Reference" "C716"
			(at 0 0 270)
			(layer "F.SilkS")
			(hide yes)
			(effects
				(font
					(size 1.27 1.27)
				)
			)
		)
		(property "Value" ""
			(at 0 0 270)
			(layer "F.Fab")
			(effects
				(font
					(size 1.27 1.27)
				)
			)
		)
		(duplicate_pad_numbers_are_jumpers no)
		(fp_line
			(start -0.299974 0.150114)
			(end -0.299974 -0.150114)
			(stroke
				(width 0.1)
				(type default)
			)
			(layer "F.Fab")
		)
		(fp_line
			(start 0.299974 0.150114)
			(end -0.299974 0.150114)
			(stroke
				(width 0.1)
				(type default)
			)
			(layer "F.Fab")
		)
		(fp_line
			(start -0.299974 -0.150114)
			(end 0.299974 -0.150114)
			(stroke
				(width 0.1)
				(type default)
			)
			(layer "F.Fab")
		)
		(fp_line
			(start 0.299974 -0.150114)
			(end 0.299974 0.150114)
			(stroke
				(width 0.1)
				(type default)
			)
			(layer "F.Fab")
		)
		(pad "1" smd rect
			(at -0.2667 0 270)
			(size 0.3048 0.381)
			(layers "F.Cu" "F.Mask" "F.Paste")
			(net "P5E_CPU1_P1_TX_C_DN<12>")
		)
		(pad "2" smd rect
			(at 0.2667 0 270)
			(size 0.3048 0.381)
			(layers "F.Cu" "F.Mask" "F.Paste")
			(net "P5E_CPU1_P1_TX_DN<12>")
		)
	)
	(footprint ""
		(layer "F.Cu")
		(at 412.75 -98.425 -90)
		(property "Reference" "R8094"
			(at 0 0 270)
			(layer "F.SilkS")
			(hide yes)
			(effects
				(font
					(size 1.27 1.27)
				)
			)
		)
		(property "Value" ""
			(at 0 0 270)
			(layer "F.Fab")
			(effects
				(font
					(size 1.27 1.27)
				)
			)
		)
		(duplicate_pad_numbers_are_jumpers no)
		(fp_line
			(start -0.7874 0.4064)
			(end -0.7874 -0.4064)
			(stroke
				(width 0.1524)
				(type default)
			)
			(layer "F.SilkS")
		)
		(fp_line
			(start 0.7874 0.4064)
			(end -0.7874 0.4064)
			(stroke
				(width 0.1524)
				(type default)
			)
			(layer "F.SilkS")
		)
		(fp_line
			(start -0.7874 -0.4064)
			(end 0.7874 -0.4064)
			(stroke
				(width 0.1524)
				(type default)
			)
			(layer "F.SilkS")
		)
		(fp_line
			(start 0.7874 -0.4064)
			(end 0.7874 0.4064)
			(stroke
				(width 0.1524)
				(type default)
			)
			(layer "F.SilkS")
		)
		(fp_line
			(start -0.67945 0.3048)
			(end -0.67945 -0.305054)
			(stroke
				(width 0.1)
				(type default)
			)
			(layer "F.Fab")
		)
		(fp_line
			(start -0.12065 0.3048)
			(end -0.67945 0.3048)
			(stroke
				(width 0.1)
				(type default)
			)
			(layer "F.Fab")
		)
		(fp_line
			(start 0.120396 0.3048)
			(end 0.120396 0.2794)
			(stroke
				(width 0.1)
				(type default)
			)
			(layer "F.Fab")
		)
		(fp_line
			(start 0.67945 0.3048)
			(end 0.120396 0.3048)
			(stroke
				(width 0.1)
				(type default)
			)
			(layer "F.Fab")
		)
		(fp_line
			(start -0.12065 0.2794)
			(end -0.12065 0.3048)
			(stroke
				(width 0.1)
				(type default)
			)
			(layer "F.Fab")
		)
		(fp_line
			(start 0.120396 0.2794)
			(end -0.12065 0.2794)
			(stroke
				(width 0.1)
				(type default)
			)
			(layer "F.Fab")
		)
		(fp_line
			(start -0.12065 -0.2794)
			(end 0.12065 -0.2794)
			(stroke
				(width 0.1)
				(type default)
			)
			(layer "F.Fab")
		)
		(fp_line
			(start 0.12065 -0.2794)
			(end 0.12065 -0.3048)
			(stroke
				(width 0.1)
				(type default)
			)
			(layer "F.Fab")
		)
		(fp_line
			(start 0.12065 -0.3048)
			(end 0.67945 -0.3048)
			(stroke
				(width 0.1)
				(type default)
			)
			(layer "F.Fab")
		)
		(fp_line
			(start 0.67945 -0.3048)
			(end 0.67945 0.3048)
			(stroke
				(width 0.1)
				(type default)
			)
			(layer "F.Fab")
		)
		(fp_line
			(start -0.67945 -0.305054)
			(end -0.12065 -0.305054)
			(stroke
				(width 0.1)
				(type default)
			)
			(layer "F.Fab")
		)
		(fp_line
			(start -0.12065 -0.305054)
			(end -0.12065 -0.2794)
			(stroke
				(width 0.1)
				(type default)
			)
			(layer "F.Fab")
		)
		(pad "1" smd circle
			(at -0.40005 0 270)
			(size 0 0)
			(layers "F.Cu" "F.Mask" "F.Paste")
			(net "OCP_V3_1_P3V3_R1_PWRGD")
		)
		(pad "2" smd circle
			(at 0.40005 0 270)
			(size 0 0)
			(layers "F.Cu" "F.Mask" "F.Paste")
			(net "OCP_V3_1_P3V3_PWRGD")
		)
	)
)
